FILE_TYPE = MACRO_DRAWING;
SET COLOR_WIRE YELLOW;
SET COLOR_PROP MONO;
SET COLOR_DOT WHITE;
SET COLOR_ARC YELLOW;
SET COLOR_BODY GREEN;
SET COLOR_NOTE MONO;
SET PROP_DISPLAY VALUE;
SET PAGE_NUMBER P136;
FORCEADD RES..2
(-2250 4800);
FORCEPROP 1 LAST LOCATION R7G26
J 0
(-2205 4925);
DISPLAY 0.617021 (-2205 4925);
PAINT AQUA (-2205 4925);
FORCEPROP 1 LAST PART_NUMBER G21796-016
J 0
(-2210 4675);
DISPLAY 0.617021 (-2210 4675);
PAINT BLUE (-2210 4675);
FORCEPROP 1 LAST VALUE 10.0K
J 0
(-2205 4875);
DISPLAY 0.617021 (-2205 4875);
PAINT SKYBLUE (-2205 4875);
FORCEPROP 1 LAST TOLERANCE 1%
J 0
(-2205 4825);
DISPLAY 0.617021 (-2205 4825);
PAINT SKYBLUE (-2205 4825);
FORCEPROP 1 LAST PACK_TYPE 0402
J 0
(-2210 4625);
DISPLAY 0.617021 (-2210 4625);
PAINT SKYBLUE (-2210 4625);
FORCEPROP 1 LAST MATERIAL CHIP
J 0
(-2210 4725);
DISPLAY 0.617021 (-2210 4725);
PAINT SKYBLUE (-2210 4725);
FORCEPROP 1 LAST WATTAGE 1/16W
J 0
(-2210 4775);
DISPLAY 0.617021 (-2210 4775);
PAINT SKYBLUE (-2210 4775);
FORCEPROP 1 LASTPIN (-2250 4700) $PN 2
J 0
(-2245 4710);
DISPLAY 0.617021 (-2245 4710);
PAINT ORANGE (-2245 4710);
FORCEPROP 1 LASTPIN (-2250 4900) $PN 1
J 0
(-2245 4862);
DISPLAY 0.617021 (-2245 4862);
PAINT ORANGE (-2245 4862);
FORCEPROP 2 LAST ROOM SB
J 0
(-2200 4975);
PAINT MONO (-2200 4975);
DISPLAY INVISIBLE (-2200 4975);
FORCEPROP 2 LAST CDS_LIB mstr_discrete
J 0
(-2250 4800);
PAINT ORANGE (-2250 4800);
DISPLAY INVISIBLE (-2250 4800);
FORCEPROP 2 LAST SEC_TYPE 0402
J 0
(-2200 5025);
DISPLAY 1.021277 (-2200 5025);
PAINT ORANGE (-2200 5025);
DISPLAY INVISIBLE (-2200 5025);
FORCEPROP 2 LAST SEC 1
J 0
(-2200 5025);
DISPLAY 0.680851 (-2200 5025);
PAINT MONO (-2200 5025);
DISPLAY INVISIBLE (-2200 5025);
FORCEPROP 1 LAST PATH I101
J 0
(-2200 4975);
DISPLAY 0.978723 (-2200 4975);
PAINT WHITE (-2200 4975);
DISPLAY INVISIBLE (-2200 4975);
FORCEADD RES..2
(-2450 3825);
FORCEPROP 1 LAST PART_NUMBER G21796-026
J 0
(-2410 3700);
DISPLAY 0.617021 (-2410 3700);
PAINT BLUE (-2410 3700);
FORCEPROP 1 LAST MATERIAL CHIP
J 0
(-2410 3750);
DISPLAY 0.617021 (-2410 3750);
PAINT SKYBLUE (-2410 3750);
FORCEPROP 1 LAST WATTAGE 1/16W
J 0
(-2410 3800);
DISPLAY 0.617021 (-2410 3800);
PAINT SKYBLUE (-2410 3800);
FORCEPROP 1 LASTPIN (-2450 3725) $PN 2
J 0
(-2445 3735);
DISPLAY 0.617021 (-2445 3735);
PAINT ORANGE (-2445 3735);
FORCEPROP 1 LAST VALUE 1.00K
J 0
(-2405 3900);
DISPLAY 0.617021 (-2405 3900);
PAINT SKYBLUE (-2405 3900);
FORCEPROP 1 LAST LOCATION R7G28
J 0
(-2400 3950);
DISPLAY 0.617021 (-2400 3950);
PAINT AQUA (-2400 3950);
FORCEPROP 1 LASTPIN (-2450 3925) $PN 1
J 0
(-2445 3887);
DISPLAY 0.617021 (-2445 3887);
PAINT ORANGE (-2445 3887);
FORCEPROP 1 LAST TOLERANCE 1%
J 0
(-2405 3850);
DISPLAY 0.617021 (-2405 3850);
PAINT SKYBLUE (-2405 3850);
FORCEPROP 1 LAST PACK_TYPE 0402
J 0
(-2410 3650);
DISPLAY 0.617021 (-2410 3650);
PAINT SKYBLUE (-2410 3650);
FORCEPROP 2 LAST ROOM SB
J 0
(-1875 3925);
PAINT PEACH (-1875 3925);
DISPLAY INVISIBLE (-1875 3925);
FORCEPROP 1 LAST PATH I102
J 0
(-2400 4000);
DISPLAY 0.978723 (-2400 4000);
PAINT WHITE (-2400 4000);
DISPLAY INVISIBLE (-2400 4000);
FORCEPROP 2 LAST SEC 1
J 0
(-2400 4050);
DISPLAY 0.680851 (-2400 4050);
PAINT MONO (-2400 4050);
DISPLAY INVISIBLE (-2400 4050);
FORCEPROP 2 LAST SEC_TYPE 0402
J 0
(-2400 4050);
DISPLAY 1.021277 (-2400 4050);
PAINT ORANGE (-2400 4050);
DISPLAY INVISIBLE (-2400 4050);
FORCEPROP 2 LAST BOM_COST SB
J 0
(-2600 3975);
PAINT ORANGE (-2600 3975);
DISPLAY INVISIBLE (-2600 3975);
FORCEPROP 2 LAST CDS_LIB mstr_discrete
J 0
(-2450 3825);
PAINT ORANGE (-2450 3825);
DISPLAY INVISIBLE (-2450 3825);
FORCEADD GND..1
(-2450 3625);
FORCEPROP 3 LASTPIN (-2450 3675) SIG_NAME GND\g
J 0
(-2440 3685);
DISPLAY 0.659574 (-2440 3685);
PAINT MONO (-2440 3685);
DISPLAY INVISIBLE (-2440 3685);
FORCEPROP 1 LAST HDL_POWER GND
J 0
(-2450 3775);
DISPLAY 1.468085 (-2450 3775);
PAINT GREEN (-2450 3775);
DISPLAY INVISIBLE (-2450 3775);
FORCEPROP 1 LAST BODY_TYPE PLUMBING
J 0
(-2495 3582);
DISPLAY 0.340426 (-2495 3582);
PAINT GREEN (-2495 3582);
DISPLAY INVISIBLE (-2495 3582);
FORCEPROP 1 LAST VOLTAGE 0
J 0
(-2450 3625);
PAINT SKYBLUE (-2450 3625);
DISPLAY INVISIBLE (-2450 3625);
FORCEPROP 1 LAST SIZE 1B
J 0
(-2375 3575);
DISPLAY 1.468085 (-2375 3575);
PAINT GREEN (-2375 3575);
DISPLAY INVISIBLE (-2375 3575);
FORCEPROP 2 LAST BOM_COST SB
J 0
(-2500 3700);
PAINT MONO (-2500 3700);
DISPLAY INVISIBLE (-2500 3700);
FORCEPROP 2 LAST CDS_LIB mstr_symbols
J 0
(-2450 3625);
PAINT ORANGE (-2450 3625);
DISPLAY INVISIBLE (-2450 3625);
FORCEPROP 1 LAST PATH I103
J 0
(-2375 3625);
DISPLAY 0.872340 (-2375 3625);
PAINT AQUA (-2375 3625);
DISPLAY INVISIBLE (-2375 3625);
FORCEADD P3V3_STBY..1
(-2250 5025);
FORCEPROP 3 LASTPIN (-2250 4975) SIG_NAME P3V3_STBY\g
J 0
(-2240 4985);
DISPLAY 0.659574 (-2240 4985);
PAINT MONO (-2240 4985);
DISPLAY INVISIBLE (-2240 4985);
FORCEPROP 1 LAST HDL_POWER P3V3_STBY
J 0
(-2550 4900);
DISPLAY 0.872340 (-2550 4900);
PAINT ORANGE (-2550 4900);
DISPLAY INVISIBLE (-2550 4900);
FORCEPROP 1 LAST BODY_TYPE PLUMBING
J 0
(-2295 4982);
DISPLAY 0.340426 (-2295 4982);
PAINT GREEN (-2295 4982);
DISPLAY INVISIBLE (-2295 4982);
FORCEPROP 1 LAST VOLTAGE 3.3V
J 0
(-2295 4982);
DISPLAY 0.340426 (-2295 4982);
PAINT SKYBLUE (-2295 4982);
DISPLAY INVISIBLE (-2295 4982);
FORCEPROP 1 LAST PATH I124
J 0
(-2205 5027);
DISPLAY 0.340426 (-2205 5027);
PAINT GREEN (-2205 5027);
DISPLAY INVISIBLE (-2205 5027);
FORCEPROP 2 LAST CDS_LIB mstr_symbols
J 0
(-2250 5025);
PAINT MONO (-2250 5025);
DISPLAY INVISIBLE (-2250 5025);
FORCEPROP 1 LAST SIZE 1B
J 0
(-2205 5047);
DISPLAY 0.340426 (-2205 5047);
PAINT GREEN (-2205 5047);
DISPLAY INVISIBLE (-2205 5047);
FORCEADD OFFPAGE..2
(1850 2300);
FORCEPROP 2 LAST $XR1 175 
J 0
(2159 2300);
DISPLAY 0.638298 (2159 2300);
PAINT MONO (2159 2300);
FORCEPROP 2 LAST $XR0 119 
J 0
(2039 2300);
DISPLAY 0.638298 (2039 2300);
PAINT MONO (2039 2300);
FORCEPROP 1 LAST COMMENT_BODY TRUE
J 0
(1805 2205);
DISPLAY 0.978723 (1805 2205);
PAINT GREEN (1805 2205);
DISPLAY INVISIBLE (1805 2205);
FORCEPROP 1 LAST OFFPAGE TRUE
J 0
(2175 2175);
PAINT GREEN (2175 2175);
DISPLAY INVISIBLE (2175 2175);
FORCEPROP 2 LAST ROOM WBG_HEADERS_BIOS
J 0
(1625 2375);
PAINT ORANGE (1625 2375);
DISPLAY INVISIBLE (1625 2375);
FORCEPROP 2 LAST CDS_LIB mstr_standard
J 0
(1850 2300);
PAINT MONO (1850 2300);
DISPLAY INVISIBLE (1850 2300);
FORCEPROP 2 LAST BOM_COST SB
J 0
(2050 2350);
PAINT ORANGE (2050 2350);
DISPLAY INVISIBLE (2050 2350);
FORCEPROP 2 LAST PATH I125
J 0
(2175 2350);
DISPLAY 1.021277 (2175 2350);
PAINT ORANGE (2175 2350);
DISPLAY INVISIBLE (2175 2350);
FORCEADD RES..1
(1000 2300);
FORCEPROP 1 LAST PART_NUMBER G21796-074
J 0
(875 2175);
DISPLAY 0.617021 (875 2175);
PAINT BLUE (875 2175);
FORCEPROP 1 LAST TOLERANCE 1%
J 0
(900 2250);
DISPLAY 0.617021 (900 2250);
PAINT SKYBLUE (900 2250);
FORCEPROP 1 LAST LOCATION R8E20
J 0
(950 2350);
DISPLAY 0.617021 (950 2350);
PAINT AQUA (950 2350);
FORCEPROP 1 LAST PACK_TYPE 0402
J 0
(1350 2250);
DISPLAY 0.617021 (1350 2250);
PAINT SKYBLUE (1350 2250);
FORCEPROP 1 LAST MATERIAL CHIP
J 0
(1000 2250);
DISPLAY 0.617021 (1000 2250);
PAINT SKYBLUE (1000 2250);
FORCEPROP 1 LAST WATTAGE 1/16W
J 2
(1475 2200);
DISPLAY 0.617021 (1475 2200);
PAINT SKYBLUE (1475 2200);
FORCEPROP 1 LASTPIN (1100 2300) $PN 2
J 0
(1062 2312);
DISPLAY 0.617021 (1062 2312);
PAINT ORANGE (1062 2312);
FORCEPROP 1 LASTPIN (900 2300) $PN 1
J 0
(912 2312);
DISPLAY 0.617021 (912 2312);
PAINT ORANGE (912 2312);
FORCEPROP 1 LAST VALUE 33.2
J 2
(850 2250);
DISPLAY 0.617021 (850 2250);
PAINT SKYBLUE (850 2250);
FORCEPROP 0 LAST ROOM SB
J 0
(950 2450);
DISPLAY 1.021277 (950 2450);
PAINT ORANGE (950 2450);
DISPLAY INVISIBLE (950 2450);
FORCEPROP 1 LAST PATH I126
J 0
(950 2450);
DISPLAY 0.978723 (950 2450);
PAINT WHITE (950 2450);
DISPLAY INVISIBLE (950 2450);
FORCEPROP 2 LAST CDS_LOCATION R8E20
J 0
(950 2350);
DISPLAY 0.617021 (950 2350);
PAINT AQUA (950 2350);
DISPLAY INVISIBLE (950 2350);
FORCEPROP 2 LAST SEC 1
J 0
(950 2500);
DISPLAY 0.680851 (950 2500);
PAINT MONO (950 2500);
DISPLAY INVISIBLE (950 2500);
FORCEPROP 0 LAST BOM_COST SB
J 0
(950 2450);
DISPLAY 1.021277 (950 2450);
PAINT ORANGE (950 2450);
DISPLAY INVISIBLE (950 2450);
FORCEPROP 2 LAST SEC_TYPE 0402
J 0
(950 2500);
DISPLAY 1.021277 (950 2500);
PAINT ORANGE (950 2500);
DISPLAY INVISIBLE (950 2500);
FORCEPROP 2 LAST CDS_LIB mstr_discrete
J 0
(1000 2300);
PAINT ORANGE (1000 2300);
DISPLAY INVISIBLE (1000 2300);
FORCEADD P3V3_STBY..1
(575 1825);
FORCEPROP 3 LASTPIN (575 1775) SIG_NAME P3V3_STBY\g
J 0
(585 1785);
DISPLAY 0.659574 (585 1785);
PAINT MONO (585 1785);
DISPLAY INVISIBLE (585 1785);
FORCEPROP 1 LAST HDL_POWER P3V3_STBY
J 0
(275 1700);
DISPLAY 0.872340 (275 1700);
PAINT ORANGE (275 1700);
DISPLAY INVISIBLE (275 1700);
FORCEPROP 1 LAST BODY_TYPE PLUMBING
J 0
(530 1782);
DISPLAY 0.340426 (530 1782);
PAINT GREEN (530 1782);
DISPLAY INVISIBLE (530 1782);
FORCEPROP 1 LAST VOLTAGE 3.3V
J 0
(530 1782);
DISPLAY 0.340426 (530 1782);
PAINT SKYBLUE (530 1782);
DISPLAY INVISIBLE (530 1782);
FORCEPROP 1 LAST PATH I127
J 0
(620 1827);
DISPLAY 0.340426 (620 1827);
PAINT GREEN (620 1827);
DISPLAY INVISIBLE (620 1827);
FORCEPROP 2 LAST CDS_LIB mstr_symbols
J 0
(575 1825);
PAINT MONO (575 1825);
DISPLAY INVISIBLE (575 1825);
FORCEPROP 1 LAST SIZE 1B
J 0
(620 1847);
DISPLAY 0.340426 (620 1847);
PAINT GREEN (620 1847);
DISPLAY INVISIBLE (620 1847);
FORCEADD CAP_A..1
(575 1575);
FORCEPROP 1 LAST LOCATION C8E8
J 0
(625 1675);
DISPLAY 0.617021 (625 1675);
PAINT AQUA (625 1675);
FORCEPROP 1 LAST PART_NUMBER A36096-030
J 0
(625 1425);
DISPLAY 0.617021 (625 1425);
PAINT BLUE (625 1425);
FORCEPROP 1 LAST VALUE 0.1UF
J 0
(625 1625);
DISPLAY 0.617021 (625 1625);
PAINT SKYBLUE (625 1625);
FORCEPROP 1 LAST TOLERANCE 10%
J 0
(625 1525);
DISPLAY 0.617021 (625 1525);
PAINT SKYBLUE (625 1525);
FORCEPROP 1 LAST PACK_TYPE 0402V
J 0
(625 1375);
DISPLAY 0.617021 (625 1375);
PAINT SKYBLUE (625 1375);
FORCEPROP 1 LAST VOLTAGE 16V
J 0
(625 1575);
DISPLAY 0.617021 (625 1575);
PAINT SKYBLUE (625 1575);
FORCEPROP 1 LAST MATERIAL X7R
J 0
(625 1475);
DISPLAY 0.617021 (625 1475);
PAINT SKYBLUE (625 1475);
FORCEPROP 1 LASTPIN (575 1675) $PN 1
J 0
(585 1655);
DISPLAY 0.617021 (585 1655);
PAINT ORANGE (585 1655);
FORCEPROP 1 LASTPIN (575 1475) $PN 2
J 0
(585 1455);
DISPLAY 0.617021 (585 1455);
PAINT ORANGE (585 1455);
FORCEPROP 2 LAST ROOM SB
J 0
(625 1725);
DISPLAY 1.021277 (625 1725);
PAINT ORANGE (625 1725);
DISPLAY INVISIBLE (625 1725);
FORCEPROP 2 LAST SEC 1
J 0
(625 1775);
DISPLAY 0.680851 (625 1775);
PAINT MONO (625 1775);
DISPLAY INVISIBLE (625 1775);
FORCEPROP 2 LAST SEC_TYPE 0402V
J 0
(625 1775);
DISPLAY 1.021277 (625 1775);
PAINT ORANGE (625 1775);
DISPLAY INVISIBLE (625 1775);
FORCEPROP 2 LAST CDS_SEC 1
J 0
(625 1725);
PAINT ORANGE (625 1725);
DISPLAY INVISIBLE (625 1725);
FORCEPROP 2 LAST CDS_LIB dev_discrete
J 0
(575 1575);
PAINT ORANGE (575 1575);
DISPLAY INVISIBLE (575 1575);
FORCEPROP 2 LAST BOM_COST SB
J 0
(625 1775);
DISPLAY 1.021277 (625 1775);
PAINT ORANGE (625 1775);
DISPLAY INVISIBLE (625 1775);
FORCEPROP 2 LAST CDS_LOCATION C8E8
J 0
(625 1675);
DISPLAY 0.617021 (625 1675);
PAINT AQUA (625 1675);
DISPLAY INVISIBLE (625 1675);
FORCEPROP 1 LAST PATH I128
J 0
(625 1725);
DISPLAY 0.978723 (625 1725);
PAINT WHITE (625 1725);
DISPLAY INVISIBLE (625 1725);
FORCEADD GND..1
(575 1300);
FORCEPROP 3 LASTPIN (575 1350) SIG_NAME GND\g
J 0
(585 1360);
DISPLAY 0.659574 (585 1360);
PAINT MONO (585 1360);
DISPLAY INVISIBLE (585 1360);
FORCEPROP 1 LAST HDL_POWER GND
J 0
(575 1450);
DISPLAY 0.872340 (575 1450);
PAINT GREEN (575 1450);
DISPLAY INVISIBLE (575 1450);
FORCEPROP 1 LAST BODY_TYPE PLUMBING
J 0
(530 1257);
DISPLAY 0.340426 (530 1257);
PAINT GREEN (530 1257);
DISPLAY INVISIBLE (530 1257);
FORCEPROP 1 LAST VOLTAGE 0.0V
J 0
(530 1257);
DISPLAY 0.340426 (530 1257);
PAINT SKYBLUE (530 1257);
DISPLAY INVISIBLE (530 1257);
FORCEPROP 1 LAST PATH I129
J 0
(650 1300);
DISPLAY 0.872340 (650 1300);
PAINT AQUA (650 1300);
DISPLAY INVISIBLE (650 1300);
FORCEPROP 2 LAST CDS_LIB mstr_symbols
J 0
(575 1300);
PAINT MONO (575 1300);
DISPLAY INVISIBLE (575 1300);
FORCEPROP 1 LAST SIZE 1B
J 0
(650 1250);
DISPLAY 0.872340 (650 1250);
PAINT AQUA (650 1250);
DISPLAY INVISIBLE (650 1250);
FORCEADD TTL1G126_A..1
(0 2300);
FORCEPROP 1 LAST PART_NUMBER A79322-001
J 0
(100 2210);
DISPLAY 0.617021 (100 2210);
PAINT BLUE (100 2210);
FORCEPROP 1 LAST POWER_GROUP VCC=P3V3_STBY;GND=GND;
J 0
(100 2160);
DISPLAY 0.617021 (100 2160);
PAINT ORANGE (100 2160);
FORCEPROP 1 LASTPIN (0 2200) $PN 1
J 0
(5 2150);
DISPLAY 0.617021 (5 2150);
PAINT WHITE (5 2150);
FORCEPROP 1 LAST LOCATION U8E3
J 0
(-50 2500);
DISPLAY 0.617021 (-50 2500);
PAINT AQUA (-50 2500);
FORCEPROP 1 LAST VALUE 74HC1G126
J 0
(-50 2400);
DISPLAY 0.617021 (-50 2400);
PAINT SKYBLUE (-50 2400);
FORCEPROP 1 LAST MATERIAL IC
J 0
(-50 2450);
DISPLAY 0.617021 (-50 2450);
PAINT SKYBLUE (-50 2450);
FORCEPROP 1 LASTPIN (150 2300) $PN 4
J 0
(115 2310);
DISPLAY 0.617021 (115 2310);
PAINT WHITE (115 2310);
FORCEPROP 1 LASTPIN (-150 2300) $PN 2
J 2
(-125 2310);
DISPLAY 0.617021 (-125 2310);
PAINT WHITE (-125 2310);
FORCEPROP 1 LAST PACK_TYPE SOT
J 0
(-50 2550);
DISPLAY 0.978723 (-50 2550);
PAINT SKYBLUE (-50 2550);
DISPLAY INVISIBLE (-50 2550);
FORCEPROP 2 LAST ROOM SB
J 0
(-50 2550);
DISPLAY 1.021277 (-50 2550);
PAINT ORANGE (-50 2550);
DISPLAY INVISIBLE (-50 2550);
FORCEPROP 1 LAST PATH I130
J 2
(-105 2400);
DISPLAY 0.978723 (-105 2400);
PAINT GREEN (-105 2400);
DISPLAY INVISIBLE (-105 2400);
FORCEPROP 2 LAST CDS_LOCATION U8E3
J 0
(-50 2500);
DISPLAY 0.617021 (-50 2500);
PAINT AQUA (-50 2500);
DISPLAY INVISIBLE (-50 2500);
FORCEPROP 2 LAST SEC 1
J 0
(-50 2550);
DISPLAY 0.680851 (-50 2550);
PAINT MONO (-50 2550);
DISPLAY INVISIBLE (-50 2550);
FORCEPROP 2 LAST CDS_LIB mstr_ttl
J 0
(0 2300);
PAINT MONO (0 2300);
DISPLAY INVISIBLE (0 2300);
FORCEPROP 2 LAST SEC_TYPE SOT
J 0
(-50 2550);
DISPLAY 1.021277 (-50 2550);
PAINT ORANGE (-50 2550);
DISPLAY INVISIBLE (-50 2550);
FORCEPROP 2 LAST BOM_COST SB
J 0
(-50 2600);
DISPLAY 1.021277 (-50 2600);
PAINT ORANGE (-50 2600);
DISPLAY INVISIBLE (-50 2600);
FORCEADD P3V3_STBY..1
(-550 2100);
FORCEPROP 3 LASTPIN (-550 2050) SIG_NAME P3V3_STBY\g
J 0
(-540 2060);
DISPLAY 0.659574 (-540 2060);
PAINT MONO (-540 2060);
DISPLAY INVISIBLE (-540 2060);
FORCEPROP 1 LAST HDL_POWER P3V3_STBY
J 0
(-850 1975);
DISPLAY 0.872340 (-850 1975);
PAINT ORANGE (-850 1975);
DISPLAY INVISIBLE (-850 1975);
FORCEPROP 1 LAST BODY_TYPE PLUMBING
J 0
(-595 2057);
DISPLAY 0.340426 (-595 2057);
PAINT GREEN (-595 2057);
DISPLAY INVISIBLE (-595 2057);
FORCEPROP 1 LAST VOLTAGE 3.3V
J 0
(-595 2057);
DISPLAY 0.340426 (-595 2057);
PAINT SKYBLUE (-595 2057);
DISPLAY INVISIBLE (-595 2057);
FORCEPROP 1 LAST PATH I131
J 0
(-505 2102);
DISPLAY 0.340426 (-505 2102);
PAINT GREEN (-505 2102);
DISPLAY INVISIBLE (-505 2102);
FORCEPROP 2 LAST CDS_LIB mstr_symbols
J 0
(-550 2100);
PAINT ORANGE (-550 2100);
DISPLAY INVISIBLE (-550 2100);
FORCEPROP 1 LAST SIZE 1B
J 0
(-505 2122);
DISPLAY 0.340426 (-505 2122);
PAINT GREEN (-505 2122);
DISPLAY INVISIBLE (-505 2122);
FORCEADD OFFPAGE..1
(-800 2300);
FORCEPROP 2 LAST $XR3 157 
J 0
(-1442 2300);
DISPLAY 0.638298 (-1442 2300);
PAINT MONO (-1442 2300);
FORCEPROP 2 LAST $XR2 145 
J 0
(-1322 2300);
DISPLAY 0.638298 (-1322 2300);
PAINT MONO (-1322 2300);
FORCEPROP 2 LAST $XR1 136 
J 0
(-1202 2300);
DISPLAY 0.638298 (-1202 2300);
PAINT MONO (-1202 2300);
FORCEPROP 2 LAST $XR0 120 
J 0
(-1082 2300);
DISPLAY 0.638298 (-1082 2300);
PAINT MONO (-1082 2300);
FORCEPROP 1 LAST COMMENT_BODY TRUE
J 0
(-675 2200);
DISPLAY 0.872340 (-675 2200);
PAINT GREEN (-675 2200);
DISPLAY INVISIBLE (-675 2200);
FORCEPROP 1 LAST OFFPAGE TRUE
J 0
(-475 2175);
DISPLAY 0.872340 (-475 2175);
PAINT GREEN (-475 2175);
DISPLAY INVISIBLE (-475 2175);
FORCEPROP 2 LAST CDS_LIB mstr_standard
J 0
(-800 2300);
PAINT MONO (-800 2300);
DISPLAY INVISIBLE (-800 2300);
FORCEPROP 2 LAST PATH I132
J 0
(-1050 2350);
DISPLAY 1.021277 (-1050 2350);
PAINT ORANGE (-1050 2350);
DISPLAY INVISIBLE (-1050 2350);
FORCEADD RES..2
(-550 1900);
FORCEPROP 1 LAST WATTAGE 1/16W
J 0
(-510 1875);
DISPLAY 0.617021 (-510 1875);
PAINT SKYBLUE (-510 1875);
FORCEPROP 1 LAST PART_NUMBER G21796-072
J 0
(-510 1775);
DISPLAY 0.617021 (-510 1775);
PAINT BLUE (-510 1775);
FORCEPROP 1 LAST VALUE 4.75K
J 0
(-505 1975);
DISPLAY 0.617021 (-505 1975);
PAINT SKYBLUE (-505 1975);
FORCEPROP 1 LAST TOLERANCE 1%
J 0
(-505 1925);
DISPLAY 0.617021 (-505 1925);
PAINT SKYBLUE (-505 1925);
FORCEPROP 1 LAST PACK_TYPE 0402
J 0
(-510 1725);
DISPLAY 0.617021 (-510 1725);
PAINT SKYBLUE (-510 1725);
FORCEPROP 1 LAST MATERIAL CHIP
J 0
(-510 1825);
DISPLAY 0.617021 (-510 1825);
PAINT SKYBLUE (-510 1825);
FORCEPROP 1 LASTPIN (-550 2000) $PN 1
J 0
(-545 1962);
DISPLAY 0.617021 (-545 1962);
PAINT ORANGE (-545 1962);
FORCEPROP 1 LASTPIN (-550 1800) $PN 2
J 0
(-545 1810);
DISPLAY 0.617021 (-545 1810);
PAINT ORANGE (-545 1810);
FORCEPROP 1 LAST LOCATION R8E14
J 0
(-505 2025);
DISPLAY 0.617021 (-505 2025);
PAINT AQUA (-505 2025);
FORCEPROP 0 LAST ROOM SB
J 0
(-500 2125);
DISPLAY 1.021277 (-500 2125);
PAINT ORANGE (-500 2125);
DISPLAY INVISIBLE (-500 2125);
FORCEPROP 1 LAST PATH I133
J 0
(-500 2075);
DISPLAY 0.978723 (-500 2075);
PAINT WHITE (-500 2075);
DISPLAY INVISIBLE (-500 2075);
FORCEPROP 2 LAST CDS_LOCATION R8E14
J 0
(-505 2025);
DISPLAY 0.617021 (-505 2025);
PAINT AQUA (-505 2025);
DISPLAY INVISIBLE (-505 2025);
FORCEPROP 2 LAST SEC 1
J 0
(-500 2125);
DISPLAY 0.680851 (-500 2125);
PAINT MONO (-500 2125);
DISPLAY INVISIBLE (-500 2125);
FORCEPROP 2 LAST SEC_TYPE 0402
J 0
(-500 2125);
DISPLAY 1.021277 (-500 2125);
PAINT ORANGE (-500 2125);
DISPLAY INVISIBLE (-500 2125);
FORCEPROP 2 LAST CDS_LIB mstr_discrete
J 0
(-550 1900);
PAINT ORANGE (-550 1900);
DISPLAY INVISIBLE (-550 1900);
FORCEADD FET_N..8
(-550 1375);
FORCEPROP 1 LAST LOCATION Q8E1
J 0
(-350 1375);
DISPLAY 0.617021 (-350 1375);
PAINT AQUA (-350 1375);
FORCEPROP 1 LAST PART_NUMBER C79254-001
J 0
(-350 1175);
DISPLAY 0.617021 (-350 1175);
PAINT BLUE (-350 1175);
FORCEPROP 1 LAST VALUE 2N7002
J 0
(-350 1325);
DISPLAY 0.617021 (-350 1325);
PAINT SKYBLUE (-350 1325);
FORCEPROP 1 LAST MATERIAL FET
J 0
(-350 1275);
DISPLAY 0.617021 (-350 1275);
PAINT SKYBLUE (-350 1275);
FORCEPROP 1 LASTPIN (-550 1575) $PN 3
J 2
(-497 1540);
DISPLAY 0.617021 (-497 1540);
PAINT WHITE (-497 1540);
FORCEPROP 1 LASTPIN (-750 1275) $PN 1
J 2
(-747 1290);
DISPLAY 0.617021 (-747 1290);
PAINT WHITE (-747 1290);
FORCEPROP 1 LASTPIN (-550 1175) $PN 2
J 2
(-492 1175);
DISPLAY 0.617021 (-492 1175);
PAINT WHITE (-492 1175);
FORCEPROP 1 LAST PACK_TYPE SOT23LF
J 0
(-350 1225);
DISPLAY 0.978723 (-350 1225);
PAINT SKYBLUE (-350 1225);
DISPLAY INVISIBLE (-350 1225);
FORCEPROP 0 LAST ROOM SB
J 0
(-350 1475);
DISPLAY 1.021277 (-350 1475);
PAINT ORANGE (-350 1475);
DISPLAY INVISIBLE (-350 1475);
FORCEPROP 1 LAST PATH I134
J 0
(-350 1425);
DISPLAY 0.978723 (-350 1425);
PAINT BLUE (-350 1425);
DISPLAY INVISIBLE (-350 1425);
FORCEPROP 2 LAST CDS_LOCATION Q8E1
J 0
(-350 1375);
DISPLAY 0.617021 (-350 1375);
PAINT AQUA (-350 1375);
DISPLAY INVISIBLE (-350 1375);
FORCEPROP 2 LAST SEC 1
J 0
(-350 1475);
DISPLAY 0.680851 (-350 1475);
PAINT MONO (-350 1475);
DISPLAY INVISIBLE (-350 1475);
FORCEPROP 2 LAST SEC_TYPE SOT23LF
J 0
(-350 1475);
DISPLAY 1.021277 (-350 1475);
PAINT ORANGE (-350 1475);
DISPLAY INVISIBLE (-350 1475);
FORCEPROP 2 LAST CDS_LIB mstr_discrete
J 0
(-550 1375);
PAINT ORANGE (-550 1375);
DISPLAY INVISIBLE (-550 1375);
FORCEADD GND..1
(-550 1075);
FORCEPROP 3 LASTPIN (-550 1125) SIG_NAME GND\g
J 0
(-540 1135);
DISPLAY 0.659574 (-540 1135);
PAINT MONO (-540 1135);
DISPLAY INVISIBLE (-540 1135);
FORCEPROP 1 LAST HDL_POWER GND
J 0
(-550 1225);
DISPLAY 0.872340 (-550 1225);
PAINT GREEN (-550 1225);
DISPLAY INVISIBLE (-550 1225);
FORCEPROP 1 LAST BODY_TYPE PLUMBING
J 0
(-595 1032);
DISPLAY 0.340426 (-595 1032);
PAINT GREEN (-595 1032);
DISPLAY INVISIBLE (-595 1032);
FORCEPROP 1 LAST VOLTAGE 0.0V
J 0
(-595 1032);
DISPLAY 0.340426 (-595 1032);
PAINT SKYBLUE (-595 1032);
DISPLAY INVISIBLE (-595 1032);
FORCEPROP 1 LAST PATH I135
J 0
(-475 1075);
DISPLAY 0.872340 (-475 1075);
PAINT AQUA (-475 1075);
DISPLAY INVISIBLE (-475 1075);
FORCEPROP 2 LAST CDS_LIB mstr_symbols
J 0
(-550 1075);
PAINT ORANGE (-550 1075);
DISPLAY INVISIBLE (-550 1075);
FORCEPROP 1 LAST SIZE 1B
J 0
(-475 1025);
DISPLAY 0.872340 (-475 1025);
PAINT AQUA (-475 1025);
DISPLAY INVISIBLE (-475 1025);
FORCEADD OFFPAGE..1
(-1225 1275);
FORCEPROP 2 LAST $XR3 247 
J 0
(-1867 1275);
DISPLAY 0.638298 (-1867 1275);
PAINT MONO (-1867 1275);
FORCEPROP 2 LAST $XR2 191 
J 0
(-1747 1275);
DISPLAY 0.638298 (-1747 1275);
PAINT MONO (-1747 1275);
FORCEPROP 2 LAST $XR1 139 
J 0
(-1627 1275);
DISPLAY 0.638298 (-1627 1275);
PAINT MONO (-1627 1275);
FORCEPROP 2 LAST $XR0 119 
J 0
(-1507 1275);
DISPLAY 0.638298 (-1507 1275);
PAINT MONO (-1507 1275);
FORCEPROP 1 LAST COMMENT_BODY TRUE
J 0
(-1100 1175);
DISPLAY 0.872340 (-1100 1175);
PAINT GREEN (-1100 1175);
DISPLAY INVISIBLE (-1100 1175);
FORCEPROP 1 LAST OFFPAGE TRUE
J 0
(-900 1150);
DISPLAY 0.872340 (-900 1150);
PAINT GREEN (-900 1150);
DISPLAY INVISIBLE (-900 1150);
FORCEPROP 2 LAST CDS_LIB mstr_standard
J 0
(-1225 1275);
PAINT ORANGE (-1225 1275);
DISPLAY INVISIBLE (-1225 1275);
FORCEPROP 2 LAST PATH I136
J 0
(-1475 1325);
DISPLAY 1.021277 (-1475 1325);
PAINT ORANGE (-1475 1325);
DISPLAY INVISIBLE (-1475 1325);
FORCEADD RES..2
(-400 4800);
FORCEPROP 1 LAST LOCATION R7G31
J 0
(-355 4925);
DISPLAY 0.617021 (-355 4925);
PAINT AQUA (-355 4925);
FORCEPROP 1 LAST VALUE 1.00K
J 0
(-355 4875);
DISPLAY 0.617021 (-355 4875);
PAINT SKYBLUE (-355 4875);
FORCEPROP 1 LAST TOLERANCE 1%
J 0
(-355 4825);
DISPLAY 0.617021 (-355 4825);
PAINT SKYBLUE (-355 4825);
FORCEPROP 1 LAST PACK_TYPE 0402
J 0
(-360 4625);
DISPLAY 0.617021 (-360 4625);
PAINT SKYBLUE (-360 4625);
FORCEPROP 1 LAST WATTAGE 1/16W
J 0
(-360 4775);
DISPLAY 0.617021 (-360 4775);
PAINT SKYBLUE (-360 4775);
FORCEPROP 1 LASTPIN (-400 4900) $PN 1
J 0
(-395 4862);
DISPLAY 0.617021 (-395 4862);
PAINT ORANGE (-395 4862);
FORCEPROP 1 LASTPIN (-400 4700) $PN 2
J 0
(-395 4710);
DISPLAY 0.617021 (-395 4710);
PAINT ORANGE (-395 4710);
FORCEPROP 1 LAST MATERIAL CHIP
J 0
(-360 4725);
DISPLAY 0.617021 (-360 4725);
PAINT SKYBLUE (-360 4725);
FORCEPROP 1 LAST PART_NUMBER G21796-026
J 0
(-360 4675);
DISPLAY 0.617021 (-360 4675);
PAINT BLUE (-360 4675);
FORCEPROP 2 LAST ROOM SB
J 0
(-450 4625);
DISPLAY 1.361702 (-450 4625);
PAINT ORANGE (-450 4625);
DISPLAY INVISIBLE (-450 4625);
FORCEPROP 2 LAST CDS_LIB mstr_discrete
J 0
(-400 4800);
PAINT ORANGE (-400 4800);
DISPLAY INVISIBLE (-400 4800);
FORCEPROP 2 LAST BOM_COST SB
R 3
J 0
(-175 4750);
PAINT ORANGE (-175 4750);
DISPLAY INVISIBLE (-175 4750);
FORCEPROP 2 LAST SEC_TYPE 0402
J 0
(-350 5025);
DISPLAY 1.021277 (-350 5025);
PAINT ORANGE (-350 5025);
DISPLAY INVISIBLE (-350 5025);
FORCEPROP 2 LAST SEC 1
J 0
(-350 5025);
DISPLAY 0.680851 (-350 5025);
PAINT MONO (-350 5025);
DISPLAY INVISIBLE (-350 5025);
FORCEPROP 1 LAST PATH I139
J 0
(-350 4975);
DISPLAY 0.978723 (-350 4975);
PAINT WHITE (-350 4975);
DISPLAY INVISIBLE (-350 4975);
FORCEADD RES..2
(0 3900);
FORCEPROP 1 LAST VALUE 20.0K
J 0
(45 3975);
DISPLAY 0.617021 (45 3975);
PAINT SKYBLUE (45 3975);
FORCEPROP 1 LAST TOLERANCE 1%
J 0
(45 3925);
DISPLAY 0.617021 (45 3925);
PAINT SKYBLUE (45 3925);
FORCEPROP 1 LASTPIN (0 4000) $PN 1
J 0
(5 3962);
DISPLAY 0.617021 (5 3962);
PAINT ORANGE (5 3962);
FORCEPROP 1 LAST PART_NUMBER G21796-040
J 0
(40 3775);
DISPLAY 0.617021 (40 3775);
PAINT BLUE (40 3775);
FORCEPROP 1 LAST PACK_TYPE 0402
J 0
(40 3725);
DISPLAY 0.617021 (40 3725);
PAINT SKYBLUE (40 3725);
FORCEPROP 1 LAST MATERIAL CHIP
J 0
(40 3825);
DISPLAY 0.617021 (40 3825);
PAINT SKYBLUE (40 3825);
FORCEPROP 1 LASTPIN (0 3800) $PN 2
J 0
(5 3810);
DISPLAY 0.617021 (5 3810);
PAINT ORANGE (5 3810);
FORCEPROP 1 LAST WATTAGE 1/16W
J 0
(40 3875);
DISPLAY 0.617021 (40 3875);
PAINT SKYBLUE (40 3875);
FORCEPROP 1 LAST LOCATION R8E16
J 0
(45 4025);
DISPLAY 0.617021 (45 4025);
PAINT AQUA (45 4025);
FORCEPROP 2 LAST ROOM SB
J 0
(45 3975);
DISPLAY 1.361702 (45 3975);
PAINT ORANGE (45 3975);
DISPLAY INVISIBLE (45 3975);
FORCEPROP 1 LAST PATH I140
J 0
(50 4075);
DISPLAY 0.978723 (50 4075);
PAINT WHITE (50 4075);
DISPLAY INVISIBLE (50 4075);
FORCEPROP 2 LAST CDS_LOCATION R8E16
J 0
(45 4025);
DISPLAY 0.617021 (45 4025);
PAINT AQUA (45 4025);
DISPLAY INVISIBLE (45 4025);
FORCEPROP 2 LAST BOM_COST SB
R 3
J 0
(175 3850);
PAINT ORANGE (175 3850);
DISPLAY INVISIBLE (175 3850);
FORCEPROP 2 LAST CDS_LIB mstr_discrete
J 0
(0 3900);
PAINT ORANGE (0 3900);
DISPLAY INVISIBLE (0 3900);
FORCEPROP 2 LAST SEC_TYPE 0402
J 0
(50 4125);
DISPLAY 1.021277 (50 4125);
PAINT ORANGE (50 4125);
DISPLAY INVISIBLE (50 4125);
FORCEPROP 2 LAST SEC 1
J 0
(50 4125);
DISPLAY 0.680851 (50 4125);
PAINT MONO (50 4125);
DISPLAY INVISIBLE (50 4125);
FORCEADD GND..1
(0 3700);
FORCEPROP 3 LASTPIN (0 3750) SIG_NAME GND\g
J 0
(10 3760);
DISPLAY 0.659574 (10 3760);
PAINT MONO (10 3760);
DISPLAY INVISIBLE (10 3760);
FORCEPROP 1 LAST HDL_POWER GND
J 0
(0 3850);
DISPLAY 0.851064 (0 3850);
PAINT GREEN (0 3850);
DISPLAY INVISIBLE (0 3850);
FORCEPROP 1 LAST BODY_TYPE PLUMBING
J 0
(-45 3657);
DISPLAY 0.340426 (-45 3657);
PAINT GREEN (-45 3657);
DISPLAY INVISIBLE (-45 3657);
FORCEPROP 1 LAST VOLTAGE 0
J 0
(0 3700);
PAINT SKYBLUE (0 3700);
DISPLAY INVISIBLE (0 3700);
FORCEPROP 2 LAST ROOM WBG_HEADERS_BIOS
J 0
(-375 3775);
PAINT ORANGE (-375 3775);
DISPLAY INVISIBLE (-375 3775);
FORCEPROP 2 LAST CDS_LIB mstr_symbols
J 0
(0 3700);
PAINT ORANGE (0 3700);
DISPLAY INVISIBLE (0 3700);
FORCEPROP 1 LAST SIZE 1B
J 0
(75 3650);
DISPLAY 0.851064 (75 3650);
PAINT GREEN (75 3650);
DISPLAY INVISIBLE (75 3650);
FORCEPROP 2 LAST BOM_COST SB
J 0
(-50 3775);
PAINT ORANGE (-50 3775);
DISPLAY INVISIBLE (-50 3775);
FORCEPROP 1 LAST PATH I141
J 0
(75 3700);
DISPLAY 0.872340 (75 3700);
PAINT AQUA (75 3700);
DISPLAY INVISIBLE (75 3700);
FORCEADD RES..2
R 2
(-2500 4800);
FORCEPROP 1 LASTPIN (-2500 4900) $PN 1
J 2
(-2505 4862);
DISPLAY 0.617021 (-2505 4862);
PAINT ORANGE (-2505 4862);
FORCEPROP 1 LASTPIN (-2500 4700) $PN 2
J 2
(-2505 4710);
DISPLAY 0.617021 (-2505 4710);
PAINT ORANGE (-2505 4710);
FORCEPROP 1 LAST MATERIAL CHIP
J 2
(-2540 4725);
DISPLAY 0.617021 (-2540 4725);
PAINT SKYBLUE (-2540 4725);
FORCEPROP 1 LAST VALUE 10.0K
J 2
(-2545 4875);
DISPLAY 0.617021 (-2545 4875);
PAINT SKYBLUE (-2545 4875);
FORCEPROP 1 LAST PART_NUMBER G21796-016
J 2
(-2540 4675);
DISPLAY 0.617021 (-2540 4675);
PAINT BLUE (-2540 4675);
FORCEPROP 1 LAST LOCATION R2N28
J 2
(-2545 4925);
DISPLAY 0.617021 (-2545 4925);
PAINT AQUA (-2545 4925);
FORCEPROP 1 LAST WATTAGE 1/16W
J 2
(-2540 4775);
DISPLAY 0.617021 (-2540 4775);
PAINT SKYBLUE (-2540 4775);
FORCEPROP 1 LAST TOLERANCE 1%
J 2
(-2545 4825);
DISPLAY 0.617021 (-2545 4825);
PAINT SKYBLUE (-2545 4825);
FORCEPROP 1 LAST PACK_TYPE 0402
J 2
(-2540 4625);
DISPLAY 0.617021 (-2540 4625);
PAINT SKYBLUE (-2540 4625);
FORCEPROP 1 LAST PATH I147
J 2
(-2550 4975);
DISPLAY 0.978723 (-2550 4975);
PAINT WHITE (-2550 4975);
DISPLAY INVISIBLE (-2550 4975);
FORCEPROP 2 LAST SEC 1
J 2
(-2550 5025);
DISPLAY 0.680851 (-2550 5025);
PAINT MONO (-2550 5025);
DISPLAY INVISIBLE (-2550 5025);
FORCEPROP 2 LAST SEC_TYPE 0402
J 2
(-2550 5025);
DISPLAY 1.021277 (-2550 5025);
PAINT ORANGE (-2550 5025);
DISPLAY INVISIBLE (-2550 5025);
FORCEPROP 2 LAST BOM_COST SB
J 2
(-2550 4975);
PAINT ORANGE (-2550 4975);
DISPLAY INVISIBLE (-2550 4975);
FORCEPROP 2 LAST CDS_LIB mstr_discrete
J 2
(-2500 4800);
PAINT MONO (-2500 4800);
DISPLAY INVISIBLE (-2500 4800);
FORCEPROP 2 LAST ROOM SB
J 2
(-2545 4875);
DISPLAY 1.361702 (-2545 4875);
PAINT ORANGE (-2545 4875);
DISPLAY INVISIBLE (-2545 4875);
FORCEADD RES..2
(-3100 3850);
FORCEPROP 1 LAST MATERIAL CHIP
J 0
(-3060 3775);
DISPLAY 0.617021 (-3060 3775);
PAINT SKYBLUE (-3060 3775);
FORCEPROP 1 LASTPIN (-3100 3950) $PN 1
J 0
(-3095 3912);
DISPLAY 0.617021 (-3095 3912);
PAINT ORANGE (-3095 3912);
FORCEPROP 1 LAST PACK_TYPE 0402
J 0
(-3060 3675);
DISPLAY 0.617021 (-3060 3675);
PAINT SKYBLUE (-3060 3675);
FORCEPROP 1 LAST WATTAGE 1/16W
J 0
(-3060 3825);
DISPLAY 0.617021 (-3060 3825);
PAINT SKYBLUE (-3060 3825);
FORCEPROP 1 LASTPIN (-3100 3750) $PN 2
J 0
(-3095 3760);
DISPLAY 0.617021 (-3095 3760);
PAINT ORANGE (-3095 3760);
FORCEPROP 1 LAST TOLERANCE 1%
J 0
(-3055 3875);
DISPLAY 0.617021 (-3055 3875);
PAINT SKYBLUE (-3055 3875);
FORCEPROP 1 LAST VALUE 1.00K
J 0
(-3055 3925);
DISPLAY 0.617021 (-3055 3925);
PAINT SKYBLUE (-3055 3925);
FORCEPROP 1 LAST PART_NUMBER G21796-026
J 0
(-3060 3725);
DISPLAY 0.617021 (-3060 3725);
PAINT BLUE (-3060 3725);
FORCEPROP 1 LAST LOCATION R7G29
J 0
(-3055 3975);
DISPLAY 0.617021 (-3055 3975);
PAINT AQUA (-3055 3975);
FORCEPROP 2 LAST ROOM SB
J 0
(-3055 3925);
DISPLAY 1.361702 (-3055 3925);
PAINT ORANGE (-3055 3925);
DISPLAY INVISIBLE (-3055 3925);
FORCEPROP 2 LAST CDS_LIB mstr_discrete
J 0
(-3100 3850);
PAINT ORANGE (-3100 3850);
DISPLAY INVISIBLE (-3100 3850);
FORCEPROP 2 LAST BOM_COST SB
R 3
J 0
(-2925 3800);
PAINT ORANGE (-2925 3800);
DISPLAY INVISIBLE (-2925 3800);
FORCEPROP 2 LAST SEC_TYPE 0402
J 0
(-3050 4075);
DISPLAY 1.021277 (-3050 4075);
PAINT ORANGE (-3050 4075);
DISPLAY INVISIBLE (-3050 4075);
FORCEPROP 2 LAST SEC 1
J 0
(-3050 4075);
DISPLAY 0.680851 (-3050 4075);
PAINT MONO (-3050 4075);
DISPLAY INVISIBLE (-3050 4075);
FORCEPROP 1 LAST PATH I148
J 0
(-3050 4025);
DISPLAY 0.978723 (-3050 4025);
PAINT WHITE (-3050 4025);
DISPLAY INVISIBLE (-3050 4025);
FORCEADD GND..1
(-3100 3650);
FORCEPROP 3 LASTPIN (-3100 3700) SIG_NAME GND\g
J 0
(-3090 3710);
DISPLAY 0.659574 (-3090 3710);
PAINT MONO (-3090 3710);
DISPLAY INVISIBLE (-3090 3710);
FORCEPROP 1 LAST HDL_POWER GND
J 0
(-3100 3800);
DISPLAY 0.851064 (-3100 3800);
PAINT GREEN (-3100 3800);
DISPLAY INVISIBLE (-3100 3800);
FORCEPROP 1 LAST BODY_TYPE PLUMBING
J 0
(-3145 3607);
DISPLAY 0.340426 (-3145 3607);
PAINT GREEN (-3145 3607);
DISPLAY INVISIBLE (-3145 3607);
FORCEPROP 1 LAST VOLTAGE 0
J 0
(-3100 3650);
PAINT SKYBLUE (-3100 3650);
DISPLAY INVISIBLE (-3100 3650);
FORCEPROP 2 LAST ROOM WBG_HEADERS_BIOS
J 0
(-3475 3725);
PAINT ORANGE (-3475 3725);
DISPLAY INVISIBLE (-3475 3725);
FORCEPROP 1 LAST PATH I152
J 0
(-3025 3650);
DISPLAY 0.872340 (-3025 3650);
PAINT AQUA (-3025 3650);
DISPLAY INVISIBLE (-3025 3650);
FORCEPROP 2 LAST BOM_COST SB
J 0
(-3150 3725);
PAINT ORANGE (-3150 3725);
DISPLAY INVISIBLE (-3150 3725);
FORCEPROP 2 LAST CDS_LIB mstr_symbols
J 0
(-3100 3650);
DISPLAY 1.148936 (-3100 3650);
PAINT ORANGE (-3100 3650);
DISPLAY INVISIBLE (-3100 3650);
FORCEPROP 1 LAST SIZE 1B
J 0
(-3025 3600);
DISPLAY 0.851064 (-3025 3600);
PAINT GREEN (-3025 3600);
DISPLAY INVISIBLE (-3025 3600);
FORCEADD P3V3_STBY..1
(-600 5025);
FORCEPROP 3 LASTPIN (-600 4975) SIG_NAME P3V3_STBY\g
J 0
(-590 4985);
DISPLAY 0.659574 (-590 4985);
PAINT MONO (-590 4985);
DISPLAY INVISIBLE (-590 4985);
FORCEPROP 1 LAST HDL_POWER P3V3_STBY
J 0
(-900 4900);
DISPLAY 0.872340 (-900 4900);
PAINT ORANGE (-900 4900);
DISPLAY INVISIBLE (-900 4900);
FORCEPROP 1 LAST BODY_TYPE PLUMBING
J 0
(-645 4982);
DISPLAY 0.340426 (-645 4982);
PAINT GREEN (-645 4982);
DISPLAY INVISIBLE (-645 4982);
FORCEPROP 2 LAST CDS_LIB mstr_symbols
J 0
(-600 5025);
PAINT MONO (-600 5025);
DISPLAY INVISIBLE (-600 5025);
FORCEPROP 1 LAST SIZE 1B
J 0
(-555 5047);
DISPLAY 0.340426 (-555 5047);
PAINT GREEN (-555 5047);
DISPLAY INVISIBLE (-555 5047);
FORCEPROP 1 LAST PATH I154
J 0
(-555 5027);
DISPLAY 0.340426 (-555 5027);
PAINT GREEN (-555 5027);
DISPLAY INVISIBLE (-555 5027);
FORCEPROP 1 LAST VOLTAGE 3.3V
J 0
(-645 4982);
DISPLAY 0.340426 (-645 4982);
PAINT SKYBLUE (-645 4982);
DISPLAY INVISIBLE (-645 4982);
FORCEADD RES..2
R 2
(-600 4800);
FORCEPROP 1 LASTPIN (-600 4700) $PN 2
J 2
(-605 4710);
DISPLAY 0.617021 (-605 4710);
PAINT ORANGE (-605 4710);
FORCEPROP 1 LAST WATTAGE 1/16W
J 2
(-640 4775);
DISPLAY 0.617021 (-640 4775);
PAINT SKYBLUE (-640 4775);
FORCEPROP 1 LASTPIN (-600 4900) $PN 1
J 2
(-605 4862);
DISPLAY 0.617021 (-605 4862);
PAINT ORANGE (-605 4862);
FORCEPROP 1 LAST PACK_TYPE 0402
J 2
(-640 4625);
DISPLAY 0.617021 (-640 4625);
PAINT SKYBLUE (-640 4625);
FORCEPROP 1 LAST PART_NUMBER G21796-026
J 2
(-640 4675);
DISPLAY 0.617021 (-640 4675);
PAINT BLUE (-640 4675);
FORCEPROP 1 LAST MATERIAL CHIP
J 2
(-640 4725);
DISPLAY 0.617021 (-640 4725);
PAINT SKYBLUE (-640 4725);
FORCEPROP 1 LAST TOLERANCE 1%
J 2
(-645 4825);
DISPLAY 0.617021 (-645 4825);
PAINT SKYBLUE (-645 4825);
FORCEPROP 1 LAST VALUE 1.00K
J 2
(-645 4875);
DISPLAY 0.617021 (-645 4875);
PAINT SKYBLUE (-645 4875);
FORCEPROP 1 LAST LOCATION R7G27
J 2
(-645 4925);
DISPLAY 0.617021 (-645 4925);
PAINT AQUA (-645 4925);
FORCEPROP 1 LAST PATH I155
J 2
(-650 4975);
DISPLAY 0.978723 (-650 4975);
PAINT WHITE (-650 4975);
DISPLAY INVISIBLE (-650 4975);
FORCEPROP 2 LAST SEC 1
J 2
(-650 5025);
PAINT MONO (-650 5025);
DISPLAY INVISIBLE (-650 5025);
FORCEPROP 2 LAST CDS_LIB mstr_discrete
J 2
(-600 4800);
PAINT MONO (-600 4800);
DISPLAY INVISIBLE (-600 4800);
FORCEPROP 2 LAST BOM_COST SB
J 2
(-450 4950);
PAINT ORANGE (-450 4950);
DISPLAY INVISIBLE (-450 4950);
FORCEPROP 2 LAST SEC_TYPE 0402
J 2
(-650 5025);
DISPLAY 1.021277 (-650 5025);
PAINT ORANGE (-650 5025);
DISPLAY INVISIBLE (-650 5025);
FORCEPROP 2 LAST ROOM SB
J 2
(-1175 4900);
PAINT PEACH (-1175 4900);
DISPLAY INVISIBLE (-1175 4900);
FORCEADD RES..2
(-300 3900);
FORCEPROP 1 LAST LOCATION R3T14
J 0
(-255 4025);
DISPLAY 0.617021 (-255 4025);
PAINT AQUA (-255 4025);
FORCEPROP 1 LAST VALUE 10.0K
J 0
(-255 3975);
DISPLAY 0.617021 (-255 3975);
PAINT SKYBLUE (-255 3975);
FORCEPROP 1 LAST TOLERANCE 1%
J 0
(-255 3925);
DISPLAY 0.617021 (-255 3925);
PAINT SKYBLUE (-255 3925);
FORCEPROP 1 LASTPIN (-300 4000) $PN 1
J 0
(-295 3962);
DISPLAY 0.617021 (-295 3962);
PAINT ORANGE (-295 3962);
FORCEPROP 1 LAST PART_NUMBER G21796-016
J 0
(-260 3775);
DISPLAY 0.617021 (-260 3775);
PAINT BLUE (-260 3775);
FORCEPROP 1 LAST PACK_TYPE 0402
J 0
(-260 3725);
DISPLAY 0.617021 (-260 3725);
PAINT SKYBLUE (-260 3725);
FORCEPROP 1 LASTPIN (-300 3800) $PN 2
J 0
(-295 3810);
DISPLAY 0.617021 (-295 3810);
PAINT ORANGE (-295 3810);
FORCEPROP 1 LAST WATTAGE 1/16W
J 0
(-260 3875);
DISPLAY 0.617021 (-260 3875);
PAINT SKYBLUE (-260 3875);
FORCEPROP 1 LAST MATERIAL CHIP
J 0
(-260 3825);
DISPLAY 0.617021 (-260 3825);
PAINT SKYBLUE (-260 3825);
FORCEPROP 2 LAST ROOM SB
J 0
(-300 3900);
PAINT MONO (-300 3900);
DISPLAY INVISIBLE (-300 3900);
FORCEPROP 2 LAST SEC_TYPE 0402
J 0
(-250 4125);
DISPLAY 1.021277 (-250 4125);
PAINT ORANGE (-250 4125);
DISPLAY INVISIBLE (-250 4125);
FORCEPROP 2 LAST CDS_LIB mstr_discrete
J 0
(-300 3900);
PAINT MONO (-300 3900);
DISPLAY INVISIBLE (-300 3900);
FORCEPROP 2 LAST BOM_COST SB
J 0
(-350 3750);
PAINT MONO (-350 3750);
DISPLAY INVISIBLE (-350 3750);
FORCEPROP 2 LAST SEC 1
J 0
(-250 4125);
PAINT MONO (-250 4125);
DISPLAY INVISIBLE (-250 4125);
FORCEPROP 1 LAST PATH I156
J 0
(-250 4075);
DISPLAY 0.978723 (-250 4075);
PAINT WHITE (-250 4075);
DISPLAY INVISIBLE (-250 4075);
FORCEADD GND..1
(-300 3700);
FORCEPROP 3 LASTPIN (-300 3750) SIG_NAME GND\g
J 0
(-290 3760);
DISPLAY 0.659574 (-290 3760);
PAINT MONO (-290 3760);
DISPLAY INVISIBLE (-290 3760);
FORCEPROP 1 LAST HDL_POWER GND
J 0
(-300 3850);
DISPLAY 1.468085 (-300 3850);
PAINT GREEN (-300 3850);
DISPLAY INVISIBLE (-300 3850);
FORCEPROP 1 LAST BODY_TYPE PLUMBING
J 0
(-345 3657);
DISPLAY 0.340426 (-345 3657);
PAINT GREEN (-345 3657);
DISPLAY INVISIBLE (-345 3657);
FORCEPROP 1 LAST VOLTAGE 0
J 0
(-300 3700);
PAINT SKYBLUE (-300 3700);
DISPLAY INVISIBLE (-300 3700);
FORCEPROP 1 LAST SIZE 1B
J 0
(-225 3650);
DISPLAY 1.468085 (-225 3650);
PAINT GREEN (-225 3650);
DISPLAY INVISIBLE (-225 3650);
FORCEPROP 2 LAST BOM_COST SB
J 0
(-350 3775);
PAINT MONO (-350 3775);
DISPLAY INVISIBLE (-350 3775);
FORCEPROP 2 LAST CDS_LIB mstr_symbols
J 0
(-300 3700);
PAINT MONO (-300 3700);
DISPLAY INVISIBLE (-300 3700);
FORCEPROP 1 LAST PATH I157
J 0
(-225 3700);
DISPLAY 0.872340 (-225 3700);
PAINT AQUA (-225 3700);
DISPLAY INVISIBLE (-225 3700);
FORCEADD OFFPAGE..2
(150 4300);
FORCEPROP 2 LAST $XR0 120 
J 0
(339 4300);
DISPLAY 0.638298 (339 4300);
PAINT MONO (339 4300);
FORCEPROP 1 LAST COMMENT_BODY TRUE
J 0
(105 4205);
DISPLAY 0.872340 (105 4205);
PAINT GREEN (105 4205);
DISPLAY INVISIBLE (105 4205);
FORCEPROP 1 LAST OFFPAGE TRUE
J 0
(475 4175);
DISPLAY 0.872340 (475 4175);
PAINT GREEN (475 4175);
DISPLAY INVISIBLE (475 4175);
FORCEPROP 2 LAST CDS_LIB mstr_standard
J 0
(150 4300);
PAINT ORANGE (150 4300);
DISPLAY INVISIBLE (150 4300);
FORCEPROP 2 LAST PATH I162
J 0
(325 4375);
DISPLAY 1.021277 (325 4375);
PAINT ORANGE (325 4375);
DISPLAY INVISIBLE (325 4375);
FORCEADD OFFPAGE..2
(150 4150);
FORCEPROP 2 LAST $XR3 136 
J 0
(699 4150);
DISPLAY 0.638298 (699 4150);
PAINT MONO (699 4150);
FORCEPROP 2 LAST $XR2 157 
J 0
(579 4150);
DISPLAY 0.638298 (579 4150);
PAINT MONO (579 4150);
FORCEPROP 2 LAST $XR1 145 
J 0
(459 4150);
DISPLAY 0.638298 (459 4150);
PAINT MONO (459 4150);
FORCEPROP 2 LAST $XR0 120 
J 0
(339 4150);
DISPLAY 0.638298 (339 4150);
PAINT MONO (339 4150);
FORCEPROP 1 LAST COMMENT_BODY TRUE
J 0
(105 4055);
DISPLAY 0.872340 (105 4055);
PAINT GREEN (105 4055);
DISPLAY INVISIBLE (105 4055);
FORCEPROP 1 LAST OFFPAGE TRUE
J 0
(475 4025);
DISPLAY 0.872340 (475 4025);
PAINT GREEN (475 4025);
DISPLAY INVISIBLE (475 4025);
FORCEPROP 2 LAST CDS_LIB mstr_standard
J 0
(150 4150);
PAINT ORANGE (150 4150);
DISPLAY INVISIBLE (150 4150);
FORCEPROP 2 LAST PATH I165
J 0
(325 4225);
DISPLAY 1.021277 (325 4225);
PAINT ORANGE (325 4225);
DISPLAY INVISIBLE (325 4225);
FORCEADD OFFPAGE..5
(-3200 4150);
FORCEPROP 2 LAST $XR0 119 
J 0
(-3455 4150);
DISPLAY 0.638298 (-3455 4150);
PAINT MONO (-3455 4150);
FORCEPROP 1 LAST COMMENT_BODY TRUE
J 0
(-3100 4075);
DISPLAY 0.872340 (-3100 4075);
PAINT GREEN (-3100 4075);
DISPLAY INVISIBLE (-3100 4075);
FORCEPROP 1 LAST OFFPAGE TRUE
J 0
(-2875 4025);
DISPLAY 0.872340 (-2875 4025);
PAINT GREEN (-2875 4025);
DISPLAY INVISIBLE (-2875 4025);
FORCEPROP 2 LAST CDS_LIB mstr_standard
J 0
(-3200 4150);
PAINT ORANGE (-3200 4150);
DISPLAY INVISIBLE (-3200 4150);
FORCEPROP 2 LAST PATH I170
J 0
(-3150 4225);
DISPLAY 1.021277 (-3150 4225);
PAINT ORANGE (-3150 4225);
DISPLAY INVISIBLE (-3150 4225);
FORCEADD CONN12_C73564003..1
(-1650 4250);
FORCEPROP 1 LAST LOCATION J7G3
J 0
(-1950 4600);
DISPLAY 0.617021 (-1950 4600);
PAINT AQUA (-1950 4600);
FORCEPROP 1 LAST PART_NUMBER C73564-003
J 0
(-1950 3950);
DISPLAY 0.617021 (-1950 3950);
PAINT BLUE (-1950 3950);
FORCEPROP 1 LAST MATERIAL CONN
J 0
(-1950 4550);
DISPLAY 0.617021 (-1950 4550);
PAINT SKYBLUE (-1950 4550);
FORCEPROP 2 LASTPIN (-1300 4350) $PN 2
J 0
(-1290 4360);
DISPLAY 0.617021 (-1290 4360);
PAINT ORANGE (-1290 4360);
FORCEPROP 2 LASTPIN (-1300 4300) $PN 4
J 0
(-1290 4310);
DISPLAY 0.617021 (-1290 4310);
PAINT ORANGE (-1290 4310);
FORCEPROP 2 LASTPIN (-1300 4250) $PN 6
J 0
(-1290 4260);
DISPLAY 0.617021 (-1290 4260);
PAINT ORANGE (-1290 4260);
FORCEPROP 2 LASTPIN (-1300 4100) $PN 12
J 0
(-1290 4110);
DISPLAY 0.617021 (-1290 4110);
PAINT ORANGE (-1290 4110);
FORCEPROP 2 LASTPIN (-1300 4150) $PN 10
J 0
(-1290 4160);
DISPLAY 0.617021 (-1290 4160);
PAINT ORANGE (-1290 4160);
FORCEPROP 2 LASTPIN (-1300 4200) $PN 8
J 0
(-1290 4210);
DISPLAY 0.617021 (-1290 4210);
PAINT ORANGE (-1290 4210);
FORCEPROP 2 LASTPIN (-2000 4250) $PN 5
J 2
(-2010 4260);
DISPLAY 0.617021 (-2010 4260);
PAINT ORANGE (-2010 4260);
FORCEPROP 2 LASTPIN (-2000 4300) $PN 3
J 2
(-2010 4310);
DISPLAY 0.617021 (-2010 4310);
PAINT ORANGE (-2010 4310);
FORCEPROP 2 LASTPIN (-2000 4200) $PN 7
J 2
(-2010 4210);
DISPLAY 0.617021 (-2010 4210);
PAINT ORANGE (-2010 4210);
FORCEPROP 2 LASTPIN (-2000 4100) $PN 11
J 2
(-2010 4110);
DISPLAY 0.617021 (-2010 4110);
PAINT ORANGE (-2010 4110);
FORCEPROP 2 LASTPIN (-2000 4150) $PN 9
J 2
(-2010 4160);
DISPLAY 0.617021 (-2010 4160);
PAINT ORANGE (-2010 4160);
FORCEPROP 2 LASTPIN (-2000 4350) $PN 1
J 2
(-2010 4360);
DISPLAY 0.617021 (-2010 4360);
PAINT ORANGE (-2010 4360);
FORCEPROP 1 LAST PACK_TYPE PIP
J 0
(-1950 4650);
PAINT SKYBLUE (-1950 4650);
DISPLAY INVISIBLE (-1950 4650);
FORCEPROP 0 LAST ROOM SB
J 0
(-1950 4700);
DISPLAY 1.021277 (-1950 4700);
PAINT ORANGE (-1950 4700);
DISPLAY INVISIBLE (-1950 4700);
FORCEPROP 2 LAST SEC_TYPE PIP
J 0
(-1950 4650);
DISPLAY 1.021277 (-1950 4650);
PAINT ORANGE (-1950 4650);
DISPLAY INVISIBLE (-1950 4650);
FORCEPROP 2 LAST SEC 1
J 0
(-1950 4650);
DISPLAY 0.680851 (-1950 4650);
PAINT MONO (-1950 4650);
DISPLAY INVISIBLE (-1950 4650);
FORCEPROP 2 LAST CDS_LIB mstr_conn
J 0
(-1650 4250);
PAINT ORANGE (-1650 4250);
DISPLAY INVISIBLE (-1650 4250);
FORCEPROP 1 LAST PATH I174
J 0
(-1650 4550);
PAINT GREEN (-1650 4550);
DISPLAY INVISIBLE (-1650 4550);
FORCEPROP 0 LAST BOM_COST SB
J 0
(-1950 4800);
DISPLAY 1.021277 (-1950 4800);
PAINT ORANGE (-1950 4800);
DISPLAY INVISIBLE (-1950 4800);
FORCEADD OFFPAGE..5
(-3200 4300);
FORCEPROP 2 LAST $XR0 119 
J 0
(-3455 4300);
DISPLAY 0.638298 (-3455 4300);
PAINT MONO (-3455 4300);
FORCEPROP 1 LAST COMMENT_BODY TRUE
J 0
(-3100 4225);
DISPLAY 0.872340 (-3100 4225);
PAINT GREEN (-3100 4225);
DISPLAY INVISIBLE (-3100 4225);
FORCEPROP 1 LAST OFFPAGE TRUE
J 0
(-2875 4175);
DISPLAY 0.872340 (-2875 4175);
PAINT GREEN (-2875 4175);
DISPLAY INVISIBLE (-2875 4175);
FORCEPROP 2 LAST CDS_LIB mstr_standard
J 0
(-3200 4300);
PAINT ORANGE (-3200 4300);
DISPLAY INVISIBLE (-3200 4300);
FORCEPROP 2 LAST PATH I175
J 0
(-3150 4375);
DISPLAY 1.021277 (-3150 4375);
PAINT ORANGE (-3150 4375);
DISPLAY INVISIBLE (-3150 4375);
FORCEADD DESIGN_NOTE..1
(1400 3375);
FORCEPROP 0 LAST L1 TOP SWAP OVERRIDE STRAP
J 0
(1200 3250);
DISPLAY 1.021277 (1200 3250);
PAINT ORANGE (1200 3250);
FORCEPROP 1 LAST COMMENT_BODY TRUE
J 0
(1425 3475);
DISPLAY 0.978723 (1425 3475);
PAINT ORANGE (1425 3475);
DISPLAY INVISIBLE (1425 3475);
FORCEPROP 2 LAST CDS_LIB mstr_symbols
J 0
(1400 3375);
PAINT ORANGE (1400 3375);
DISPLAY INVISIBLE (1400 3375);
FORCEADD CAD_NOTE..1
(-1800 3400);
FORCEPROP 0 LAST L1 PLACE TO THE RIGHT OF BT8G1
J 0
(-1950 3275);
DISPLAY 1.021277 (-1950 3275);
PAINT ORANGE (-1950 3275);
FORCEPROP 1 LAST COMMENT_BODY TRUE
J 0
(-1775 3500);
DISPLAY 0.978723 (-1775 3500);
PAINT ORANGE (-1775 3500);
DISPLAY INVISIBLE (-1775 3500);
FORCEPROP 2 LAST CDS_LIB mstr_symbols
J 0
(-1800 3400);
PAINT ORANGE (-1800 3400);
DISPLAY INVISIBLE (-1800 3400);
FORCEADD BOM_NOTE..1
(-4950 3125);
FORCEPROP 0 LAST L1 4 JUMPER HEADERS (IPN 634479-007) ADDED IN MOD FILE
J 0
(-5100 2975);
DISPLAY 0.808511 (-5100 2975);
PAINT ORANGE (-5100 2975);
FORCEPROP 1 LAST COMMENT_BODY TRUE
J 0
(-4925 3225);
DISPLAY 0.978723 (-4925 3225);
PAINT ORANGE (-4925 3225);
DISPLAY INVISIBLE (-4925 3225);
FORCEPROP 2 LAST CDS_LIB mstr_symbols
J 0
(-4950 3125);
PAINT ORANGE (-4950 3125);
DISPLAY INVISIBLE (-4950 3125);
FORCEADD DESIGN_NOTE..1
(-4050 3750);
FORCEPROP 0 LAST L1 PASSWORD CLEAR
J 0
(-4250 3625);
DISPLAY 1.021277 (-4250 3625);
PAINT ORANGE (-4250 3625);
FORCEPROP 1 LAST COMMENT_BODY TRUE
J 0
(-4025 3850);
DISPLAY 0.978723 (-4025 3850);
PAINT ORANGE (-4025 3850);
DISPLAY INVISIBLE (-4025 3850);
FORCEPROP 2 LAST CDS_LIB mstr_symbols
J 0
(-4050 3750);
PAINT ORANGE (-4050 3750);
DISPLAY INVISIBLE (-4050 3750);
FORCEADD INTEL_CORP_BPAGE..1
(2650 500);
FORCEPROP 1 LAST CDS_CON_LAST_MODIFIED Fri Jun 16 17:48:52 2017
J 0
(1225 825);
PAINT ORANGE (1225 825);
DISPLAY INVISIBLE (1225 825);
FORCEPROP 1 LAST CUSTOM_TXT_CDS <CURRENT_DESIGN_SHEET> OF <TOTAL_DESIGN_SHEETS>
J 0
(2150 525);
PAINT ORANGE (2150 525);
FORCEPROP 1 LAST CUSTOM_TXT_CDS <CON_LAST_MODIFIED>
J 0
(-1350 600);
PAINT ORANGE (-1350 600);
FORCEPROP 2 LAST CUSTOM_TXT_CDS <XR_PAGE_TITLE>
J 0
(-5240 5750);
DISPLAY 0.638298 (-5240 5750);
PAINT PINK (-5240 5750);
DISPLAY INVISIBLE (-5240 5750);
FORCEPROP 1 LAST SCH_TITLE LBG HEADERS (2/3)
J 0
(-5300 550);
DISPLAY 1.212766 (-5300 550);
PAINT ORANGE (-5300 550);
FORCEPROP 1 LAST COMMENT_BODY TRUE
J 0
(2662 512);
DISPLAY 0.468085 (2662 512);
PAINT GREEN (2662 512);
DISPLAY INVISIBLE (2662 512);
FORCEPROP 2 LAST ROOM WBG_HEADERS_BIOS
J 0
(-5225 5800);
PAINT MONO (-5225 5800);
DISPLAY INVISIBLE (-5225 5800);
FORCEPROP 2 LAST CDS_LIB mstr_symbols
J 0
(2650 500);
PAINT MONO (2650 500);
DISPLAY INVISIBLE (2650 500);
FORCEPROP 2 LAST PAGE_BORDER TRUE
J 0
(-5240 5750);
DISPLAY 0.851064 (-5240 5750);
PAINT PINK (-5240 5750);
DISPLAY INVISIBLE (-5240 5750);
FORCEPROP 2 LAST BOM_COST SB
J 0
(-5225 5800);
PAINT MONO (-5225 5800);
DISPLAY INVISIBLE (-5225 5800);
FORCEPROP 2 LAST CDS_XR_PAGE_TITLE CR-136 : @BASEBOARD_FAB2_LIB.BASEBOARD_FAB2(SCH_1):PAGE136
J 0
(-5240 5750);
DISPLAY 0.638298 (-5240 5750);
PAINT PINK (-5240 5750);
DISPLAY INVISIBLE (-5240 5750);
FORCEADD CAD_NOTE..1
(1000 1825);
FORCEPROP 0 LAST L1 PLACE CAP CLOSE TO VCC ON U8E3
J 0
(850 1700);
DISPLAY 1.021277 (850 1700);
PAINT ORANGE (850 1700);
FORCEPROP 1 LAST COMMENT_BODY TRUE
J 0
(1025 1925);
DISPLAY 0.978723 (1025 1925);
PAINT ORANGE (1025 1925);
DISPLAY INVISIBLE (1025 1925);
FORCEPROP 2 LAST CDS_LIB mstr_symbols
J 0
(1000 1825);
PAINT MONO (1000 1825);
DISPLAY INVISIBLE (1000 1825);
FORCEADD DESIGN_NOTE..1
(-4075 5200);
FORCEPROP 0 LAST L1 ME FW UPDATE
J 0
(-4275 5075);
DISPLAY 1.021277 (-4275 5075);
PAINT ORANGE (-4275 5075);
FORCEPROP 1 LAST COMMENT_BODY TRUE
J 0
(-4050 5300);
DISPLAY 1.361702 (-4050 5300);
PAINT WHITE (-4050 5300);
DISPLAY INVISIBLE (-4050 5300);
FORCEPROP 2 LAST CDS_LIB mstr_symbols
J 0
(-4075 5200);
PAINT ORANGE (-4075 5200);
DISPLAY INVISIBLE (-4075 5200);
FORCEADD DESIGN_NOTE..1
(1400 3850);
FORCEPROP 0 LAST L1 BIOS RECOVERY MODE JUMPER
J 0
(1200 3725);
DISPLAY 1.021277 (1200 3725);
PAINT ORANGE (1200 3725);
FORCEPROP 1 LAST COMMENT_BODY TRUE
J 0
(1425 3950);
DISPLAY 1.361702 (1425 3950);
PAINT WHITE (1425 3950);
DISPLAY INVISIBLE (1425 3950);
FORCEPROP 2 LAST CDS_LIB mstr_symbols
J 0
(1400 3850);
PAINT ORANGE (1400 3850);
DISPLAY INVISIBLE (1400 3850);
FORCEADD DESIGN_NOTE..1
(550 5125);
FORCEPROP 0 LAST L1 BIOS USB RECOVERY
J 0
(350 5000);
DISPLAY 1.021277 (350 5000);
PAINT ORANGE (350 5000);
FORCEPROP 1 LAST COMMENT_BODY TRUE
J 0
(575 5225);
DISPLAY 1.361702 (575 5225);
PAINT WHITE (575 5225);
DISPLAY INVISIBLE (575 5225);
FORCEPROP 2 LAST CDS_LIB mstr_symbols
J 0
(550 5125);
PAINT MONO (550 5125);
DISPLAY INVISIBLE (550 5125);
WIRE 16 -1 (-2450 3725)(-2450 3675);
WIRE 16 -1 (-2250 4950)(-2250 4975);
WIRE 16 -1 (-2500 4950)(-2250 4950);
WIRE 16 -1 (-2250 4900)(-2250 4950);
WIRE 16 -1 (-2500 4900)(-2500 4950);
WIRE 16 -1 (575 1675)(575 1775);
WIRE 16 -1 (575 1350)(575 1475);
WIRE 16 -1 (-550 2000)(-550 2050);
WIRE 16 -1 (-550 1125)(-550 1175);
WIRE 16 -1 (0 3800)(0 3750);
WIRE 16 -1 (-3100 3700)(-3100 3750);
WIRE 16 -1 (-600 4950)(-600 4975);
WIRE 16 -1 (-400 4950)(-600 4950);
WIRE 16 -1 (-600 4900)(-600 4950);
WIRE 16 -1 (-400 4900)(-400 4950);
WIRE 16 -1 (-300 3800)(-300 3750);
WIRE 16 -1 (1250 3600)(1850 3600);
WIRE 16 -1 (-3425 2900)(-5125 2900);
WIRE 16 -1 (-3425 1675)(-3425 2900);
WIRE 16 -1 (-5125 2900)(-5125 1675);
WIRE 16 -1 (-5125 1675)(-3425 1675);
WIRE 16 -1 (-4300 5025)(-4300 4800);
WIRE 16 -1 (-3300 5025)(-4300 5025);
WIRE 16 -1 (-4300 4800)(-3300 4800);
WIRE 16 -1 (-3300 4800)(-3300 5025);
WIRE 16 -1 (375 4850)(1450 4850);
WIRE 16 -1 (550 4925)(550 4750);
WIRE 16 682 (-1950 975)(-1950 2800);
WIRE 16 682 (-1950 2800)(2575 2800);
WIRE 16 -1 (-4075 5000)(-4075 4825);
WIRE 16 -1 (-1175 1275)(-750 1275);
FORCEPROP 2 LAST SIG_NAME RST_PLTRST_N
J 0
(-1110 1285);
DISPLAY 0.617021 (-1110 1285);
PAINT ORANGE (-1110 1285);
WIRE 16 -1 (-4025 3575)(-4025 3400);
WIRE 16 -1 (-5075 1975)(-3450 1975);
WIRE 16 -1 (-4250 4925)(-3450 4925);
WIRE 16 -1 (-5075 2250)(-3450 2250);
WIRE 16 -1 (-5100 2525)(-3475 2525);
WIRE 16 -1 (-5100 2750)(-3475 2750);
WIRE 16 -1 (-4450 2875)(-4450 1700);
WIRE 16 -1 (1425 3675)(1425 3500);
WIRE 16 -1 (1200 3700)(1200 3475);
WIRE 16 -1 (1900 3700)(1200 3700);
WIRE 16 -1 (1200 3475)(1900 3475);
WIRE 16 -1 (1900 3475)(1900 3700);
WIRE 16 -1 (-600 4250)(-1300 4250);
WIRE 16 -1 (-600 4700)(-600 4250);
FORCEPROP 2 LAST SIG_NAME PU_BIOS_USB_RECOVERY
J 0
(-1185 4260);
DISPLAY 0.617021 (-1185 4260);
PAINT ORANGE (-1185 4260);
FORCEPROP 2 LASTPROP $XRERR UNIQUE?
J 0
(-1425 4260);
DISPLAY 0.638298 (-1425 4260);
PAINT MONO (-1425 4260);
DISPLAY INVISIBLE (-1425 4260);
WIRE 16 -1 (-400 4100)(-1300 4100);
WIRE 16 -1 (-400 4700)(-400 4100);
FORCEPROP 2 LAST SIG_NAME PU_BIOS_RECOVER_BOOT
J 0
(-1185 4110);
DISPLAY 0.617021 (-1185 4110);
PAINT ORANGE (-1185 4110);
FORCEPROP 2 LASTPROP $XRERR UNIQUE?
J 0
(-1425 4110);
DISPLAY 0.638298 (-1425 4110);
PAINT MONO (-1425 4110);
DISPLAY INVISIBLE (-1425 4110);
WIRE 16 -1 (0 4000)(0 4150);
WIRE 16 -1 (100 4150)(0 4150);
WIRE 16 -1 (-1300 4150)(0 4150);
FORCEPROP 2 LAST SIG_NAME FM_BIOS_TOP_SWAP
J 0
(-1185 4160);
DISPLAY 0.638298 (-1185 4160);
PAINT ORANGE (-1185 4160);
WIRE 16 -1 (-300 4000)(-300 4300);
WIRE 16 -1 (100 4300)(-300 4300);
WIRE 16 -1 (-1300 4300)(-300 4300);
FORCEPROP 2 LAST SIG_NAME FM_BIOS_USB_RECOVERY
J 0
(-1185 4310);
DISPLAY 0.638298 (-1185 4310);
PAINT ORANGE (-1185 4310);
WIRE 16 -1 (-1300 4200)(100 4200);
FORCEPROP 2 LAST SIG_NAME TP_BIOS_RECOVER_BOOT
J 0
(-1185 4210);
DISPLAY 0.638298 (-1185 4210);
PAINT ORANGE (-1185 4210);
FORCEPROP 2 LASTPROP $XRERR UNIQUE?
J 0
(130 4200);
DISPLAY 0.638298 (130 4200);
PAINT MONO (130 4200);
DISPLAY INVISIBLE (130 4200);
WIRE 16 -1 (-1300 4350)(125 4350);
FORCEPROP 2 LAST SIG_NAME TP_BIOS_USB_RECOVERY
J 0
(-1185 4360);
DISPLAY 0.638298 (-1185 4360);
PAINT ORANGE (-1185 4360);
FORCEPROP 2 LASTPROP $XRERR UNIQUE?
J 0
(155 4350);
DISPLAY 0.638298 (155 4350);
PAINT MONO (155 4350);
DISPLAY INVISIBLE (155 4350);
WIRE 16 -1 (325 4950)(325 4725);
WIRE 16 -1 (1475 4950)(325 4950);
WIRE 16 -1 (325 4725)(1475 4725);
WIRE 16 -1 (1475 4725)(1475 4950);
WIRE 16 -1 (-4200 3500)(-3475 3500);
WIRE 16 -1 (-2500 4700)(-2500 4150);
WIRE 16 -1 (-2500 4150)(-2000 4150);
WIRE 16 -1 (-3150 4150)(-2500 4150);
FORCEPROP 2 LAST SIG_NAME FM_PASSWORD_CLEAR_N
J 0
(-3085 4160);
DISPLAY 0.617021 (-3085 4160);
PAINT ORANGE (-3085 4160);
WIRE 16 -1 (-3150 4350)(-2000 4350);
FORCEPROP 2 LAST SIG_NAME TP_ME_RCVR_BOOT
J 0
(-3085 4360);
DISPLAY 0.617021 (-3085 4360);
PAINT ORANGE (-3085 4360);
FORCEPROP 2 LASTPROP $XRERR UNIQUE?
J 0
(-3390 4350);
DISPLAY 0.638298 (-3390 4350);
PAINT MONO (-3390 4350);
DISPLAY INVISIBLE (-3390 4350);
WIRE 16 -1 (-3150 4200)(-2000 4200);
FORCEPROP 2 LAST SIG_NAME TP_PASSWORD_CLEAR
J 0
(-3085 4210);
DISPLAY 0.617021 (-3085 4210);
PAINT ORANGE (-3085 4210);
FORCEPROP 2 LASTPROP $XRERR UNIQUE?
J 0
(-3390 4200);
DISPLAY 0.638298 (-3390 4200);
PAINT MONO (-3390 4200);
DISPLAY INVISIBLE (-3390 4200);
WIRE 16 -1 (-2450 4250)(-2000 4250);
WIRE 16 -1 (-2450 3925)(-2450 4250);
FORCEPROP 2 LAST SIG_NAME PD_ME_RCVR_N
J 0
(-2435 4260);
DISPLAY 0.617021 (-2435 4260);
PAINT ORANGE (-2435 4260);
FORCEPROP 2 LASTPROP $XRERR UNIQUE?
J 0
(-2675 4260);
DISPLAY 0.638298 (-2675 4260);
PAINT MONO (-2675 4260);
DISPLAY INVISIBLE (-2675 4260);
WIRE 16 -1 (-3100 4100)(-2000 4100);
WIRE 16 -1 (-3100 3950)(-3100 4100);
FORCEPROP 2 LAST SIG_NAME PD_PASSWORD_CLEAR
J 0
(-3085 4110);
DISPLAY 0.617021 (-3085 4110);
PAINT ORANGE (-3085 4110);
FORCEPROP 2 LASTPROP $XRERR UNIQUE?
J 0
(-3325 4110);
DISPLAY 0.638298 (-3325 4110);
PAINT MONO (-3325 4110);
DISPLAY INVISIBLE (-3325 4110);
WIRE 16 -1 (-3150 4300)(-2250 4300);
WIRE 16 -1 (-2250 4300)(-2000 4300);
WIRE 16 -1 (-2250 4700)(-2250 4300);
FORCEPROP 2 LAST SIG_NAME FM_ME_RECOVER_N
J 0
(-3085 4310);
DISPLAY 0.617021 (-3085 4310);
PAINT ORANGE (-3085 4310);
WIRE 16 -1 (-4250 3600)(-4250 3375);
WIRE 16 -1 (-3425 3600)(-4250 3600);
WIRE 16 -1 (-4250 3375)(-3425 3375);
WIRE 16 -1 (-3425 3375)(-3425 3600);
WIRE 16 -1 (150 2300)(900 2300);
FORCEPROP 2 LAST SIG_NAME FM_BIOS_TOP_SWAP_SPKR_R
J 0
(215 2310);
DISPLAY 0.617021 (215 2310);
PAINT ORANGE (215 2310);
FORCEPROP 2 LASTPROP $XRERR UNIQUE?
J 0
(-25 2310);
DISPLAY 0.638298 (-25 2310);
PAINT MONO (-25 2310);
DISPLAY INVISIBLE (-25 2310);
WIRE 16 -1 (1100 2300)(1800 2300);
FORCEPROP 0 LAST SIG_NAME FM_BIOS_TOP_SWAP_SPKR
J 0
(1140 2310);
DISPLAY 0.617021 (1140 2310);
PAINT ORANGE (1140 2310);
WIRE 16 -1 (-550 1575)(-550 1625);
WIRE 16 -1 (-550 1800)(-550 1625);
WIRE 16 -1 (-550 1625)(0 1625);
FORCEPROP 0 LAST SIG_NAME RST_PLTRST_TOP_SWAP
J 0
(-510 1650);
DISPLAY 0.617021 (-510 1650);
PAINT ORANGE (-510 1650);
FORCEPROP 2 LASTPROP $XRERR UNIQUE?
J 0
(-750 1650);
DISPLAY 0.638298 (-750 1650);
PAINT MONO (-750 1650);
DISPLAY INVISIBLE (-750 1650);
WIRE 16 -1 (0 1625)(0 2200);
WIRE 16 -1 (-150 2300)(-750 2300);
FORCEPROP 2 LAST SIG_NAME FM_BIOS_TOP_SWAP
J 0
(-685 2310);
DISPLAY 0.617021 (-685 2310);
PAINT ORANGE (-685 2310);
DOT 1 (-2500 4150);
DOT 1 (0 4150);
DOT 1 (-300 4300);
DOT 1 (-600 4950);
DOT 1 (-550 1625);
DOT 1 (-2250 4950);
DOT 1 (-2250 4300);
FORCENOTE
NORMAL<DEFAULT>
(-4000 3525) 0;
DISPLAY LEFT (-4000 3525);
DISPLAY 0.617021 (-4000 3525);
PAINT PURPLE (-4000 3525);
FORCENOTE
PASSWORD CLEAR
(-4000 3425) 0;
DISPLAY LEFT (-4000 3425);
DISPLAY 0.617021 (-4000 3425);
PAINT PURPLE (-4000 3425);
FORCENOTE
BIOS USB FLASH RECOVERY MODE
(600 4750) 0;
DISPLAY LEFT (600 4750);
DISPLAY 0.617021 (600 4750);
PAINT PURPLE (600 4750);
FORCENOTE
NORMAL OPERATION <DEFAULT>
(600 4875) 0;
DISPLAY LEFT (600 4875);
DISPLAY 0.617021 (600 4875);
PAINT PURPLE (600 4875);
FORCENOTE
8-10
(1250 3625) 0;
DISPLAY LEFT (1250 3625);
DISPLAY 0.617021 (1250 3625);
PAINT PURPLE (1250 3625);
FORCENOTE
10-12
(1250 3525) 0;
DISPLAY LEFT (1250 3525);
DISPLAY 0.617021 (1250 3525);
PAINT PURPLE (1250 3525);
FORCENOTE
NORMAL<DEFAULT>
(1450 3625) 0;
DISPLAY LEFT (1450 3625);
DISPLAY 0.617021 (1450 3625);
PAINT PURPLE (1450 3625);
FORCENOTE
RECOVER BIOS
(1450 3525) 0;
DISPLAY LEFT (1450 3525);
DISPLAY 0.617021 (1450 3525);
PAINT PURPLE (1450 3525);
FORCENOTE
4-6
(375 4750) 0;
DISPLAY LEFT (375 4750);
DISPLAY 0.617021 (375 4750);
PAINT PURPLE (375 4750);
FORCENOTE
2-4
(375 4875) 0;
DISPLAY LEFT (375 4875);
DISPLAY 0.617021 (375 4875);
PAINT PURPLE (375 4875);
FORCENOTE
TOP SWAP CIRCUITRY
(-1825 2650) 0;
DISPLAY LEFT (-1825 2650);
DISPLAY 1.021277 (-1825 2650);
PAINT PURPLE (-1825 2650);
FORCENOTE
ME FORCE UPDATE
(-4425 2550) 0;
DISPLAY LEFT (-4425 2550);
DISPLAY 1.021277 (-4425 2550);
PAINT PURPLE (-4425 2550);
FORCENOTE
NORMAL FUNCTIONALITY
(-4425 2425) 0;
DISPLAY LEFT (-4425 2425);
DISPLAY 1.021277 (-4425 2425);
PAINT PURPLE (-4425 2425);
FORCENOTE
9-11
(-4200 3425) 0;
DISPLAY LEFT (-4200 3425);
DISPLAY 0.617021 (-4200 3425);
PAINT PURPLE (-4200 3425);
FORCENOTE
NORMAL FUNCTIONALITY
(-4425 2125) 0;
DISPLAY LEFT (-4425 2125);
DISPLAY 1.021277 (-4425 2125);
PAINT PURPLE (-4425 2125);
FORCENOTE
PASSWORD CLEAR
(-4425 2300) 0;
DISPLAY LEFT (-4425 2300);
DISPLAY 1.021277 (-4425 2300);
PAINT PURPLE (-4425 2300);
FORCENOTE
RECOVER BIOS
(-4425 1750) 0;
DISPLAY LEFT (-4425 1750);
DISPLAY 1.021277 (-4425 1750);
PAINT PURPLE (-4425 1750);
FORCENOTE
NORMAL FUNCTIONALITY
(-4425 1875) 0;
DISPLAY LEFT (-4425 1875);
DISPLAY 1.021277 (-4425 1875);
PAINT PURPLE (-4425 1875);
FORCENOTE
BIOS USB FLASH RECVRY MODE
(-4425 2000) 0;
DISPLAY LEFT (-4425 2000);
DISPLAY 1.021277 (-4425 2000);
PAINT PURPLE (-4425 2000);
FORCENOTE
NORMAL FUNCTIONALITY
(-4425 2675) 0;
DISPLAY LEFT (-4425 2675);
DISPLAY 1.021277 (-4425 2675);
PAINT PURPLE (-4425 2675);
FORCENOTE
SYSTEM BEHAVIOR
(-4425 2800) 0;
DISPLAY LEFT (-4425 2800);
DISPLAY 1.021277 (-4425 2800);
PAINT PURPLE (-4425 2800);
FORCENOTE
3-5
(-4250 4850) 0;
DISPLAY LEFT (-4250 4850);
DISPLAY 0.617021 (-4250 4850);
PAINT PURPLE (-4250 4850);
FORCENOTE
1-3
(-4250 4950) 0;
DISPLAY LEFT (-4250 4950);
DISPLAY 0.617021 (-4250 4950);
PAINT PURPLE (-4250 4950);
FORCENOTE
7-9
(-4200 3525) 0;
DISPLAY LEFT (-4200 3525);
DISPLAY 0.617021 (-4200 3525);
PAINT PURPLE (-4200 3525);
FORCENOTE
1-3
(-4625 2675) 0;
DISPLAY LEFT (-4625 2675);
DISPLAY 1.021277 (-4625 2675);
PAINT PURPLE (-4625 2675);
FORCENOTE
3-5
(-4625 2550) 0;
DISPLAY LEFT (-4625 2550);
DISPLAY 1.021277 (-4625 2550);
PAINT PURPLE (-4625 2550);
FORCENOTE
2-4
(-4625 2125) 0;
DISPLAY LEFT (-4625 2125);
DISPLAY 1.021277 (-4625 2125);
PAINT PURPLE (-4625 2125);
FORCENOTE
9-11
(-4625 2300) 0;
DISPLAY LEFT (-4625 2300);
DISPLAY 1.021277 (-4625 2300);
PAINT PURPLE (-4625 2300);
FORCENOTE
7-9
(-4625 2425) 0;
DISPLAY LEFT (-4625 2425);
DISPLAY 1.021277 (-4625 2425);
PAINT PURPLE (-4625 2425);
FORCENOTE
JUMPER LOCATION
(-5050 2800) 0;
DISPLAY LEFT (-5050 2800);
DISPLAY 1.021277 (-5050 2800);
PAINT PURPLE (-5050 2800);
FORCENOTE
8-10
(-4625 1875) 0;
DISPLAY LEFT (-4625 1875);
DISPLAY 1.021277 (-4625 1875);
PAINT PURPLE (-4625 1875);
FORCENOTE
10-12
(-4625 1750) 0;
DISPLAY LEFT (-4625 1750);
DISPLAY 1.021277 (-4625 1750);
PAINT PURPLE (-4625 1750);
FORCENOTE
ROOM=SB
(-5079 842) 0;
DISPLAY LEFT (-5079 842);
DISPLAY 0.617021 (-5079 842);
PAINT PURPLE (-5079 842);
FORCENOTE
4-6
(-4625 2000) 0;
DISPLAY LEFT (-4625 2000);
DISPLAY 1.021277 (-4625 2000);
PAINT PURPLE (-4625 2000);
FORCENOTE
ME FORCE UPDATE
(-4050 4850) 0;
DISPLAY LEFT (-4050 4850);
DISPLAY 0.617021 (-4050 4850);
PAINT PURPLE (-4050 4850);
FORCENOTE
NORMAL <DEFAULT>
(-4050 4950) 0;
DISPLAY LEFT (-4050 4950);
DISPLAY 0.617021 (-4050 4950);
PAINT PURPLE (-4050 4950);
QUIT
